(kicad_pcb
	(version 20260206)
	(generator "pcbnew")
	(generator_version "10.0")
	(general
		(thickness 1.6)
		(legacy_teardrops no)
	)
	(paper "A4")
	(title_block
		(title "timecard-production-celestica-r4006 — R4006-B0001-02_R01.brd")
		(comment 1 "Time Appliance Project (Time Card) / footprints 25-30 of 1113")
	)
	(layers
		(0 "F.Cu" signal "TOP")
		(4 "In1.Cu" signal "L02_GND1")
		(6 "In2.Cu" signal "L03_SIG1")
		(8 "In3.Cu" signal "L04_GND2")
		(10 "In4.Cu" signal "L05_VCC1")
		(12 "In5.Cu" signal "L06_VCC2")
		(14 "In6.Cu" signal "L07_GND3")
		(16 "In7.Cu" signal "L08_SIG2")
		(18 "In8.Cu" signal "L09_GND4")
		(2 "B.Cu" signal "BOTTOM")
		(9 "F.Adhes" user "F.Adhesive")
		(11 "B.Adhes" user "B.Adhesive")
		(13 "F.Paste" user "Package Geometry/Pastemask Top")
		(15 "B.Paste" user "Package Geometry/Pastemask Bottom")
		(5 "F.SilkS" user "Ref Des/Silkscreen Top")
		(7 "B.SilkS" user "Ref Des/Silkscreen Bottom")
		(1 "F.Mask" user "Board Geometry/Soldermask Top")
		(3 "B.Mask" user "Board Geometry/Soldermask Bottom")
		(17 "Dwgs.User" user "User.Drawings")
		(19 "Cmts.User" user "User.Comments")
		(21 "Eco1.User" user "User.Eco1")
		(23 "Eco2.User" user "User.Eco2")
		(25 "Edge.Cuts" user "Board Geometry/Outline")
		(27 "Margin" user)
		(31 "F.CrtYd" user "Package Geometry/Place Bound Top")
		(29 "B.CrtYd" user "Package Geometry/Place Bound Bottom")
		(35 "F.Fab" user "Ref Des/Assembly Top")
		(33 "B.Fab" user "Ref Des/Assembly Bottom")
	)
	(footprint ""
		(layer "F.Cu")
		(at 10.7188 -68.201032 90)
		(property "Reference" "R375"
			(at 3.426968 -0.39243 90)
			(unlocked yes)
			(layer "F.SilkS")
			(effects
				(font
					(size 0.7874 0.5842)
					(thickness 0.1524)
				)
			)
		)
		(property "Value" "VAL*"
			(at 0.02032 2.13233 90)
			(unlocked yes)
			(layer "F.Fab")
			(hide yes)
			(effects
				(font
					(size 0.7874 0.5842)
					(thickness 0.1524)
				)
			)
		)
		(property "Device Type" "RESISTOR-G155-11000-01,100OHM,A"
			(at 0.008382 1.210564 90)
			(unlocked yes)
			(layer "F.Fab")
			(hide yes)
			(effects
				(font
					(size 0.7874 0.5842)
					(thickness 0.1524)
				)
			)
		)
		(property "User Part Number" "PARTNUM*"
			(at 0.02032 4.024884 90)
			(unlocked yes)
			(layer "Cmts.User")
			(hide yes)
			(effects
				(font
					(size 0.7874 0.5842)
					(thickness 0.1524)
				)
			)
		)
		(property "Tolerance" "TOL*"
			(at 0.044704 3.05435 90)
			(unlocked yes)
			(layer "Cmts.User")
			(hide yes)
			(effects
				(font
					(size 0.7874 0.5842)
					(thickness 0.1524)
				)
			)
		)
		(duplicate_pad_numbers_are_jumpers no)
		(fp_line
			(start 1.143 -0.5588)
			(end -1.143 -0.5588)
			(stroke
				(width 0.1)
				(type default)
			)
			(layer "F.SilkS")
		)
		(fp_line
			(start -1.143 -0.5588)
			(end -1.143 0.5588)
			(stroke
				(width 0.1)
				(type default)
			)
			(layer "F.SilkS")
		)
		(fp_line
			(start 1.143 0.5588)
			(end 1.143 -0.5588)
			(stroke
				(width 0.1)
				(type default)
			)
			(layer "F.SilkS")
		)
		(fp_line
			(start -1.143 0.5588)
			(end 1.143 0.5588)
			(stroke
				(width 0.1)
				(type default)
			)
			(layer "F.SilkS")
		)
		(fp_poly
			(pts
				(xy -1.143 0.5588) (xy 1.143 0.5588) (xy 1.143 -0.5588) (xy -1.143 -0.5588)
			)
			(stroke
				(width 0)
				(type default)
			)
			(fill no)
			(layer "F.CrtYd")
		)
		(fp_line
			(start 0.508 -0.3048)
			(end -0.508 -0.3048)
			(stroke
				(width 0.1)
				(type default)
			)
			(layer "F.Fab")
		)
		(fp_line
			(start -0.508 -0.3048)
			(end -0.508 0.3048)
			(stroke
				(width 0.1)
				(type default)
			)
			(layer "F.Fab")
		)
		(fp_line
			(start 0.508 0.3048)
			(end 0.508 -0.3048)
			(stroke
				(width 0.1)
				(type default)
			)
			(layer "F.Fab")
		)
		(fp_line
			(start -0.508 0.3048)
			(end 0.508 0.3048)
			(stroke
				(width 0.1)
				(type default)
			)
			(layer "F.Fab")
		)
		(pad "1" smd rect
			(at -0.5334 0 90)
			(size 0.7112 0.6096)
			(layers "F.Cu" "F.Mask" "F.Paste")
			(net "FPGA_OUT_SMA3_LED_GREEN_N")
		)
		(pad "2" smd rect
			(at 0.5334 0 90)
			(size 0.7112 0.6096)
			(layers "F.Cu" "F.Mask" "F.Paste")
			(net "UNNAMED_14_LED4PV14_I267_4")
		)
		(zone
			(layer "F.Cu")
			(hatch none 0.5)
			(connect_pads
				(clearance 0)
			)
			(min_thickness 0.25)
			(keepout
				(tracks allowed)
				(vias not_allowed)
				(pads allowed)
				(copperpour not_allowed)
				(footprints allowed)
			)
			(placement
				(enabled no)
				(sheetname "")
			)
			(fill
				(thermal_gap 0.5)
				(thermal_bridge_width 0.5)
				(island_removal_mode 0)
			)
			(polygon
				(pts
					(xy 11.0236 -68.124832) (xy 11.0236 -68.277232) (xy 10.414 -68.277232) (xy 10.414 -68.124832)
				)
			)
		)
		(zone
			(layer "F.Cu")
			(hatch none 0.5)
			(connect_pads
				(clearance 0)
			)
			(min_thickness 0.25)
			(keepout
				(tracks not_allowed)
				(vias allowed)
				(pads allowed)
				(copperpour not_allowed)
				(footprints allowed)
			)
			(placement
				(enabled no)
				(sheetname "")
			)
			(fill
				(thermal_gap 0.5)
				(thermal_bridge_width 0.5)
				(island_removal_mode 0)
			)
			(polygon
				(pts
					(xy 11.0236 -68.124832) (xy 11.0236 -68.277232) (xy 10.414 -68.277232) (xy 10.414 -68.124832)
				)
			)
		)
	)
	(footprint ""
		(layer "F.Cu")
		(at 64.897 -120.269)
		(property "Reference" "SP30"
			(at 0 0 0)
			(layer "F.SilkS")
			(hide yes)
			(effects
				(font
					(size 1.27 1.27)
				)
			)
		)
		(property "Value" ""
			(at 0 0 0)
			(layer "F.Fab")
			(effects
				(font
					(size 1.27 1.27)
				)
			)
		)
		(duplicate_pad_numbers_are_jumpers no)
	)
	(footprint ""
		(layer "F.Cu")
		(at 36.7284 -97.8154 180)
		(property "Reference" "R294"
			(at -2.43586 -5.93725 0)
			(unlocked yes)
			(layer "F.SilkS")
			(effects
				(font
					(size 0.7874 0.5842)
					(thickness 0.1524)
				)
			)
		)
		(property "Value" "VAL*"
			(at 0.02032 2.13233 180)
			(unlocked yes)
			(layer "F.Fab")
			(hide yes)
			(effects
				(font
					(size 0.7874 0.5842)
					(thickness 0.1524)
				)
			)
		)
		(property "Device Type" "RESISTOR-G155-133R0-01,33OHM,1%"
			(at 0.008382 1.210564 180)
			(unlocked yes)
			(layer "F.Fab")
			(hide yes)
			(effects
				(font
					(size 0.7874 0.5842)
					(thickness 0.1524)
				)
			)
		)
		(property "User Part Number" "PARTNUM*"
			(at 0.02032 4.024884 180)
			(unlocked yes)
			(layer "Cmts.User")
			(hide yes)
			(effects
				(font
					(size 0.7874 0.5842)
					(thickness 0.1524)
				)
			)
		)
		(property "Tolerance" "TOL*"
			(at 0.044704 3.05435 180)
			(unlocked yes)
			(layer "Cmts.User")
			(hide yes)
			(effects
				(font
					(size 0.7874 0.5842)
					(thickness 0.1524)
				)
			)
		)
		(duplicate_pad_numbers_are_jumpers no)
		(fp_line
			(start 1.143 0.5588)
			(end 1.143 -0.5588)
			(stroke
				(width 0.1)
				(type default)
			)
			(layer "F.SilkS")
		)
		(fp_line
			(start 1.143 -0.5588)
			(end -1.143 -0.5588)
			(stroke
				(width 0.1)
				(type default)
			)
			(layer "F.SilkS")
		)
		(fp_line
			(start -1.143 0.5588)
			(end 1.143 0.5588)
			(stroke
				(width 0.1)
				(type default)
			)
			(layer "F.SilkS")
		)
		(fp_line
			(start -1.143 -0.5588)
			(end -1.143 0.5588)
			(stroke
				(width 0.1)
				(type default)
			)
			(layer "F.SilkS")
		)
		(fp_rect
			(start -1.143 0.5588)
			(end 1.143 -0.5588)
			(stroke
				(width 0)
				(type default)
			)
			(fill no)
			(layer "F.CrtYd")
		)
		(fp_line
			(start 0.508 0.3048)
			(end 0.508 -0.3048)
			(stroke
				(width 0.1)
				(type default)
			)
			(layer "F.Fab")
		)
		(fp_line
			(start 0.508 -0.3048)
			(end -0.508 -0.3048)
			(stroke
				(width 0.1)
				(type default)
			)
			(layer "F.Fab")
		)
		(fp_line
			(start -0.508 0.3048)
			(end 0.508 0.3048)
			(stroke
				(width 0.1)
				(type default)
			)
			(layer "F.Fab")
		)
		(fp_line
			(start -0.508 -0.3048)
			(end -0.508 0.3048)
			(stroke
				(width 0.1)
				(type default)
			)
			(layer "F.Fab")
		)
		(pad "1" smd rect
			(at -0.5334 0 180)
			(size 0.7112 0.6096)
			(layers "F.Cu" "F.Mask" "F.Paste")
			(net "XP5R0V_PG")
		)
		(pad "2" smd rect
			(at 0.5334 0 180)
			(size 0.7112 0.6096)
			(layers "F.Cu" "F.Mask" "F.Paste")
			(net "FPGA_CFG_INIT_N")
		)
		(zone
			(layer "F.Cu")
			(hatch none 0.5)
			(connect_pads
				(clearance 0)
			)
			(min_thickness 0.25)
			(keepout
				(tracks allowed)
				(vias not_allowed)
				(pads allowed)
				(copperpour not_allowed)
				(footprints allowed)
			)
			(placement
				(enabled no)
				(sheetname "")
			)
			(fill
				(thermal_gap 0.5)
				(thermal_bridge_width 0.5)
				(island_removal_mode 0)
			)
			(polygon
				(pts
					(xy 36.8046 -98.1202) (xy 36.6522 -98.1202) (xy 36.6522 -97.5106) (xy 36.8046 -97.5106)
				)
			)
		)
	)
	(footprint ""
		(layer "F.Cu")
		(at 30.34538 -17.99844 180)
		(property "Reference" "R19"
			(at 1.27 5.04063 0)
			(unlocked yes)
			(layer "F.SilkS")
			(effects
				(font
					(size 0.7874 0.5842)
					(thickness 0.1524)
				)
			)
		)
		(property "Value" "VAL*"
			(at 0.02032 2.13233 180)
			(unlocked yes)
			(layer "F.Fab")
			(hide yes)
			(effects
				(font
					(size 0.7874 0.5842)
					(thickness 0.1524)
				)
			)
		)
		(property "Tolerance" "TOL*"
			(at 0.044704 3.05435 180)
			(unlocked yes)
			(layer "Cmts.User")
			(hide yes)
			(effects
				(font
					(size 0.7874 0.5842)
					(thickness 0.1524)
				)
			)
		)
		(property "User Part Number" "PARTNUM*"
			(at 0.02032 4.024884 180)
			(unlocked yes)
			(layer "Cmts.User")
			(hide yes)
			(effects
				(font
					(size 0.7874 0.5842)
					(thickness 0.1524)
				)
			)
		)
		(property "Device Type" "RESISTOR-G155-11002-01,10KOHM,A"
			(at 0.008382 1.210564 180)
			(unlocked yes)
			(layer "F.Fab")
			(hide yes)
			(effects
				(font
					(size 0.7874 0.5842)
					(thickness 0.1524)
				)
			)
		)
		(duplicate_pad_numbers_are_jumpers no)
		(fp_line
			(start 1.143 0.5588)
			(end 1.143 -0.5588)
			(stroke
				(width 0.1)
				(type default)
			)
			(layer "F.SilkS")
		)
		(fp_line
			(start 1.143 -0.5588)
			(end -1.143 -0.5588)
			(stroke
				(width 0.1)
				(type default)
			)
			(layer "F.SilkS")
		)
		(fp_line
			(start -1.143 0.5588)
			(end 1.143 0.5588)
			(stroke
				(width 0.1)
				(type default)
			)
			(layer "F.SilkS")
		)
		(fp_line
			(start -1.143 -0.5588)
			(end -1.143 0.5588)
			(stroke
				(width 0.1)
				(type default)
			)
			(layer "F.SilkS")
		)
		(fp_rect
			(start 1.143 -0.5588)
			(end -1.143 0.5588)
			(stroke
				(width 0)
				(type default)
			)
			(fill no)
			(layer "F.CrtYd")
		)
		(fp_line
			(start 0.508 0.3048)
			(end 0.508 -0.3048)
			(stroke
				(width 0.1)
				(type default)
			)
			(layer "F.Fab")
		)
		(fp_line
			(start 0.508 -0.3048)
			(end -0.508 -0.3048)
			(stroke
				(width 0.1)
				(type default)
			)
			(layer "F.Fab")
		)
		(fp_line
			(start -0.508 0.3048)
			(end 0.508 0.3048)
			(stroke
				(width 0.1)
				(type default)
			)
			(layer "F.Fab")
		)
		(fp_line
			(start -0.508 -0.3048)
			(end -0.508 0.3048)
			(stroke
				(width 0.1)
				(type default)
			)
			(layer "F.Fab")
		)
		(pad "1" smd rect
			(at -0.5334 0 180)
			(size 0.7112 0.6096)
			(layers "F.Cu" "F.Mask" "F.Paste")
			(net "XP3R3V_FPGA")
		)
		(pad "2" smd rect
			(at 0.5334 0 180)
			(size 0.7112 0.6096)
			(layers "F.Cu" "F.Mask" "F.Paste")
			(net "EEPROM_SCL")
		)
		(zone
			(layer "F.Cu")
			(hatch none 0.5)
			(connect_pads
				(clearance 0)
			)
			(min_thickness 0.25)
			(keepout
				(tracks allowed)
				(vias not_allowed)
				(pads allowed)
				(copperpour not_allowed)
				(footprints allowed)
			)
			(placement
				(enabled no)
				(sheetname "")
			)
			(fill
				(thermal_gap 0.5)
				(thermal_bridge_width 0.5)
				(island_removal_mode 0)
			)
			(polygon
				(pts
					(xy 30.26918 -17.69364) (xy 30.42158 -17.69364) (xy 30.42158 -18.30324) (xy 30.26918 -18.30324)
				)
			)
		)
	)
	(footprint ""
		(layer "F.Cu")
		(at 92.075 -84.074 180)
		(property "Reference" "U23"
			(at -0.5334 -3.79857 0)
			(unlocked yes)
			(layer "F.SilkS")
			(effects
				(font
					(size 0.7874 0.5842)
					(thickness 0.1524)
				)
			)
		)
		(property "Value" ""
			(at 0 0 180)
			(layer "F.Fab")
			(effects
				(font
					(size 1.27 1.27)
				)
			)
		)
		(property "User Part Number" "PARTNUM*"
			(at 0 5.133848 180)
			(unlocked yes)
			(layer "Cmts.User")
			(hide yes)
			(effects
				(font
					(size 0.7874 0.5842)
					(thickness 0.1524)
				)
			)
		)
		(property "Device Type" "MT25QL128ABA1ESE_SOP8-G221-102A"
			(at 0 4.092448 180)
			(unlocked yes)
			(layer "F.Fab")
			(hide yes)
			(effects
				(font
					(size 0.7874 0.5842)
					(thickness 0.1524)
				)
			)
		)
		(duplicate_pad_numbers_are_jumpers no)
		(fp_line
			(start 4.826 2.998978)
			(end 4.826 -2.998978)
			(stroke
				(width 0.1)
				(type default)
			)
			(layer "F.SilkS")
		)
		(fp_line
			(start 4.826 -2.998978)
			(end -4.826 -2.998978)
			(stroke
				(width 0.1)
				(type default)
			)
			(layer "F.SilkS")
		)
		(fp_line
			(start -4.826 2.998978)
			(end 4.826 2.998978)
			(stroke
				(width 0.1)
				(type default)
			)
			(layer "F.SilkS")
		)
		(fp_line
			(start -4.826 -2.998978)
			(end -4.826 2.998978)
			(stroke
				(width 0.1)
				(type default)
			)
			(layer "F.SilkS")
		)
		(fp_poly
			(pts
				(arc
					(start -5.969 -3.429)
					(mid -5.207 -3.429)
					(end -5.969 -3.429)
				)
			)
			(stroke
				(width 0)
				(type default)
			)
			(fill yes)
			(layer "F.SilkS")
		)
		(fp_rect
			(start 5.08 -3.252978)
			(end -5.08 3.252978)
			(stroke
				(width 0)
				(type default)
			)
			(fill no)
			(layer "F.CrtYd")
		)
		(fp_line
			(start 2.744978 2.744978)
			(end 2.744978 -2.744978)
			(stroke
				(width 0.1)
				(type default)
			)
			(layer "F.Fab")
		)
		(fp_line
			(start 2.744978 -2.744978)
			(end -2.744978 -2.744978)
			(stroke
				(width 0.1)
				(type default)
			)
			(layer "F.Fab")
		)
		(fp_line
			(start -2.744978 2.744978)
			(end 2.744978 2.744978)
			(stroke
				(width 0.1)
				(type default)
			)
			(layer "F.Fab")
		)
		(fp_line
			(start -2.744978 -2.744978)
			(end -2.744978 2.744978)
			(stroke
				(width 0.1)
				(type default)
			)
			(layer "F.Fab")
		)
		(fp_circle
			(center -4.133342 -2.39014)
			(end -4.514342 -2.39014)
			(stroke
				(width 0.1)
				(type default)
			)
			(fill no)
			(layer "F.Fab")
		)
		(fp_text user "5"
			(at 4.1656 3.82143 0)
			(unlocked yes)
			(layer "F.SilkS")
			(effects
				(font
					(size 0.7874 0.5842)
					(thickness 0.1524)
				)
			)
		)
		(fp_text user "8"
			(at 3.9116 -3.92557 0)
			(unlocked yes)
			(layer "F.SilkS")
			(effects
				(font
					(size 0.7874 0.5842)
					(thickness 0.1524)
				)
			)
		)
		(fp_text user "4"
			(at -5.3594 1.84785 0)
			(unlocked yes)
			(layer "F.SilkS")
			(effects
				(font
					(size 0.635 0.4064)
					(thickness 0.1524)
				)
			)
		)
		(fp_text user "5"
			(at 3.683 1.49733 0)
			(unlocked yes)
			(layer "F.Fab")
			(effects
				(font
					(size 0.7874 0.5842)
					(thickness 0.1524)
				)
			)
		)
		(fp_text user "8"
			(at 3.683 -2.31267 0)
			(unlocked yes)
			(layer "F.Fab")
			(effects
				(font
					(size 0.7874 0.5842)
					(thickness 0.1524)
				)
			)
		)
		(fp_text user "4"
			(at -3.4544 2.31013 0)
			(unlocked yes)
			(layer "F.Fab")
			(effects
				(font
					(size 0.7874 0.5842)
					(thickness 0.1524)
				)
			)
		)
		(pad "1" smd rect
			(at -3.6576 -1.905 180)
			(size 1.8288 0.508)
			(layers "F.Cu" "F.Mask" "F.Paste")
			(net "FLASH_CS_N")
		)
		(pad "2" smd rect
			(at -3.6576 -0.635 180)
			(size 1.8288 0.508)
			(layers "F.Cu" "F.Mask" "F.Paste")
			(net "UNNAMED_127_MT25QL128ABA1ESES_1")
		)
		(pad "3" smd rect
			(at -3.6576 0.635 180)
			(size 1.8288 0.508)
			(layers "F.Cu" "F.Mask" "F.Paste")
			(net "UNNAMED_127_MT25QL128ABA1ESES_3")
		)
		(pad "4" smd rect
			(at -3.6576 1.905 180)
			(size 1.8288 0.508)
			(layers "F.Cu" "F.Mask" "F.Paste")
			(net "SG")
		)
		(pad "5" smd rect
			(at 3.6576 1.905 180)
			(size 1.8288 0.508)
			(layers "F.Cu" "F.Mask" "F.Paste")
			(net "UNNAMED_127_MT25QL128ABA1ESESOP")
		)
		(pad "6" smd rect
			(at 3.6576 0.635 180)
			(size 1.8288 0.508)
			(layers "F.Cu" "F.Mask" "F.Paste")
			(net "FLASH_CLK")
		)
		(pad "7" smd rect
			(at 3.6576 -0.635 180)
			(size 1.8288 0.508)
			(layers "F.Cu" "F.Mask" "F.Paste")
			(net "UNNAMED_127_MT25QL128ABA1ESES_2")
		)
		(pad "8" smd rect
			(at 3.6576 -1.905 180)
			(size 1.8288 0.508)
			(layers "F.Cu" "F.Mask" "F.Paste")
			(net "XP3R3V_FPGA")
		)
	)
	(footprint ""
		(layer "F.Cu")
		(at 124.587 -51.435 180)
		(property "Reference" "R95"
			(at -0.127 -2.45237 0)
			(unlocked yes)
			(layer "F.SilkS")
			(effects
				(font
					(size 0.7874 0.5842)
					(thickness 0.1524)
				)
			)
		)
		(property "Value" "VAL*"
			(at 0.02032 2.13233 180)
			(unlocked yes)
			(layer "F.Fab")
			(hide yes)
			(effects
				(font
					(size 0.7874 0.5842)
					(thickness 0.1524)
				)
			)
		)
		(property "Tolerance" "TOL*"
			(at 0.044704 3.05435 180)
			(unlocked yes)
			(layer "Cmts.User")
			(hide yes)
			(effects
				(font
					(size 0.7874 0.5842)
					(thickness 0.1524)
				)
			)
		)
		(property "User Part Number" "PARTNUM*"
			(at 0.02032 4.024884 180)
			(unlocked yes)
			(layer "Cmts.User")
			(hide yes)
			(effects
				(font
					(size 0.7874 0.5842)
					(thickness 0.1524)
				)
			)
		)
		(property "Device Type" "RESISTOR-G155-133R0-01,33OHM,1%"
			(at 0.008382 1.210564 180)
			(unlocked yes)
			(layer "F.Fab")
			(hide yes)
			(effects
				(font
					(size 0.7874 0.5842)
					(thickness 0.1524)
				)
			)
		)
		(duplicate_pad_numbers_are_jumpers no)
		(fp_line
			(start 1.143 0.5588)
			(end 1.143 -0.5588)
			(stroke
				(width 0.1)
				(type default)
			)
			(layer "F.SilkS")
		)
		(fp_line
			(start 1.143 -0.5588)
			(end -1.143 -0.5588)
			(stroke
				(width 0.1)
				(type default)
			)
			(layer "F.SilkS")
		)
		(fp_line
			(start -1.143 0.5588)
			(end 1.143 0.5588)
			(stroke
				(width 0.1)
				(type default)
			)
			(layer "F.SilkS")
		)
		(fp_line
			(start -1.143 -0.5588)
			(end -1.143 0.5588)
			(stroke
				(width 0.1)
				(type default)
			)
			(layer "F.SilkS")
		)
		(fp_rect
			(start 1.143 -0.5588)
			(end -1.143 0.5588)
			(stroke
				(width 0)
				(type default)
			)
			(fill no)
			(layer "F.CrtYd")
		)
		(fp_line
			(start 0.508 0.3048)
			(end 0.508 -0.3048)
			(stroke
				(width 0.1)
				(type default)
			)
			(layer "F.Fab")
		)
		(fp_line
			(start 0.508 -0.3048)
			(end -0.508 -0.3048)
			(stroke
				(width 0.1)
				(type default)
			)
			(layer "F.Fab")
		)
		(fp_line
			(start -0.508 0.3048)
			(end 0.508 0.3048)
			(stroke
				(width 0.1)
				(type default)
			)
			(layer "F.Fab")
		)
		(fp_line
			(start -0.508 -0.3048)
			(end -0.508 0.3048)
			(stroke
				(width 0.1)
				(type default)
			)
			(layer "F.Fab")
		)
		(pad "1" smd rect
			(at -0.5334 0 180)
			(size 0.7112 0.6096)
			(layers "F.Cu" "F.Mask" "F.Paste")
			(net "R_MAC_UART_RX_FPGA_TX")
		)
		(pad "2" smd rect
			(at 0.5334 0 180)
			(size 0.7112 0.6096)
			(layers "F.Cu" "F.Mask" "F.Paste")
			(net "UART_MAC_RX_FPGA_TX")
		)
		(zone
			(layer "F.Cu")
			(hatch none 0.5)
			(connect_pads
				(clearance 0)
			)
			(min_thickness 0.25)
			(keepout
				(tracks allowed)
				(vias not_allowed)
				(pads allowed)
				(copperpour not_allowed)
				(footprints allowed)
			)
			(placement
				(enabled no)
				(sheetname "")
			)
			(fill
				(thermal_gap 0.5)
				(thermal_bridge_width 0.5)
				(island_removal_mode 0)
			)
			(polygon
				(pts
					(xy 124.5108 -51.1302) (xy 124.6632 -51.1302) (xy 124.6632 -51.7398) (xy 124.5108 -51.7398)
				)
			)
		)
	)
)
